# T6G (Grand Teton) — schematic netlist excerpt (pin names and nets, part order shuffled) for the footprints in the layout excerpt that follows; sources: Cadence DE-HDL packaged netlist, KiCad conversion of 04192023_DAF0TMB3IC0_F0TG_MB_C_brd_V02_OCP.brd

C6046  Q_CAP  22UF 6.3V 20% X6S  pkg C0603  page 177 : A = P3V3_AUX ; B = GND
C2031  Q_CAP  1UF 25V 10% X6S  pkg C0402  page 234 : A = P3V3_AUX_USB_HUB ; B = GND
C546  Q_CAP  10UF 25V 10% X6S  pkg C0805  page 108 : A = P12V_MEM_CPU1 ; B = GND

(kicad_pcb
	(version 20260206)
	(generator "pcbnew")
	(generator_version "10.0")
	(general
		(thickness 1.6)
		(legacy_teardrops no)
	)
	(paper "A4")
	(title_block
		(title "04192023_DAF0TMB3IC0_F0TG_MB_C_brd_V02_OCP.brd")
		(comment 1 "Grand Teton / footprints 7735-7737 of 8354")
	)
	(layers
		(0 "F.Cu" signal "TOP")
		(4 "In1.Cu" signal "GND")
		(6 "In2.Cu" signal "IN1")
		(8 "In3.Cu" signal "GND1")
		(10 "In4.Cu" signal "IN2")
		(12 "In5.Cu" signal "GND2")
		(14 "In6.Cu" signal "IN3")
		(16 "In7.Cu" signal "GND3")
		(18 "In8.Cu" signal "VCC")
		(20 "In9.Cu" signal "VCC1")
		(22 "In10.Cu" signal "GND4")
		(24 "In11.Cu" signal "IN4")
		(26 "In12.Cu" signal "GND5")
		(28 "In13.Cu" signal "IN5")
		(30 "In14.Cu" signal "GND6")
		(32 "In15.Cu" signal "IN6")
		(34 "In16.Cu" signal "GND7")
		(2 "B.Cu" signal "BOTTOM")
		(9 "F.Adhes" user "F.Adhesive")
		(11 "B.Adhes" user "B.Adhesive")
		(13 "F.Paste" user "Package Geometry/Pastemask Top")
		(15 "B.Paste" user "Package Geometry/Pastemask Bottom")
		(5 "F.SilkS" user "Ref Des/Silkscreen Top")
		(7 "B.SilkS" user "Ref Des/Silkscreen Bottom")
		(1 "F.Mask" user "Board Geometry/Soldermask Top")
		(3 "B.Mask" user "Board Geometry/Soldermask Bottom")
		(17 "Dwgs.User" user "User.Drawings")
		(19 "Cmts.User" user "User.Comments")
		(21 "Eco1.User" user "User.Eco1")
		(23 "Eco2.User" user "User.Eco2")
		(25 "Edge.Cuts" user "Board Geometry/Outline")
		(27 "Margin" user)
		(31 "F.CrtYd" user "Package Geometry/Place Bound Top")
		(29 "B.CrtYd" user "Package Geometry/Place Bound Bottom")
		(35 "F.Fab" user "Ref Des/Assembly Top")
		(33 "B.Fab" user "Ref Des/Assembly Bottom")
	)
	(footprint ""
		(layer "B.Cu")
		(at 138.112246 -32.135318 -90)
		(property "Reference" "C6046"
			(at 0 0 90)
			(layer "B.SilkS")
			(hide yes)
			(effects
				(font
					(size 1.27 1.27)
				)
				(justify mirror)
			)
		)
		(property "Value" ""
			(at 0 0 90)
			(layer "B.Fab")
			(effects
				(font
					(size 1.27 1.27)
				)
				(justify mirror)
			)
		)
		(duplicate_pad_numbers_are_jumpers no)
		(fp_line
			(start -1.2954 0.5842)
			(end 1.2954 0.5842)
			(stroke
				(width 0.1524)
				(type default)
			)
			(layer "B.SilkS")
		)
		(fp_line
			(start 1.2954 0.5842)
			(end 1.2954 -0.5842)
			(stroke
				(width 0.1524)
				(type default)
			)
			(layer "B.SilkS")
		)
		(fp_line
			(start -1.2954 -0.5842)
			(end -1.2954 0.5842)
			(stroke
				(width 0.1524)
				(type default)
			)
			(layer "B.SilkS")
		)
		(fp_line
			(start 1.2954 -0.5842)
			(end -1.2954 -0.5842)
			(stroke
				(width 0.1524)
				(type default)
			)
			(layer "B.SilkS")
		)
		(fp_line
			(start -0.8636 0.4572)
			(end 0.8636 0.4572)
			(stroke
				(width 0.1)
				(type default)
			)
			(layer "B.Fab")
		)
		(fp_line
			(start 0.8636 0.4572)
			(end 0.8636 0.4064)
			(stroke
				(width 0.1)
				(type default)
			)
			(layer "B.Fab")
		)
		(fp_line
			(start -1.1938 0.4064)
			(end -0.8636 0.4064)
			(stroke
				(width 0.1)
				(type default)
			)
			(layer "B.Fab")
		)
		(fp_line
			(start -0.8636 0.4064)
			(end -0.8636 0.4572)
			(stroke
				(width 0.1)
				(type default)
			)
			(layer "B.Fab")
		)
		(fp_line
			(start 0.8636 0.4064)
			(end 1.1938 0.4064)
			(stroke
				(width 0.1)
				(type default)
			)
			(layer "B.Fab")
		)
		(fp_line
			(start 1.1938 0.4064)
			(end 1.1938 -0.4064)
			(stroke
				(width 0.1)
				(type default)
			)
			(layer "B.Fab")
		)
		(fp_line
			(start -1.1938 -0.4064)
			(end -1.1938 0.4064)
			(stroke
				(width 0.1)
				(type default)
			)
			(layer "B.Fab")
		)
		(fp_line
			(start -0.8636 -0.4064)
			(end -1.1938 -0.4064)
			(stroke
				(width 0.1)
				(type default)
			)
			(layer "B.Fab")
		)
		(fp_line
			(start 0.8636 -0.4064)
			(end 0.8636 -0.4572)
			(stroke
				(width 0.1)
				(type default)
			)
			(layer "B.Fab")
		)
		(fp_line
			(start 1.1938 -0.4064)
			(end 0.8636 -0.4064)
			(stroke
				(width 0.1)
				(type default)
			)
			(layer "B.Fab")
		)
		(fp_line
			(start -0.8636 -0.4572)
			(end -0.8636 -0.4064)
			(stroke
				(width 0.1)
				(type default)
			)
			(layer "B.Fab")
		)
		(fp_line
			(start 0.8636 -0.4572)
			(end -0.8636 -0.4572)
			(stroke
				(width 0.1)
				(type default)
			)
			(layer "B.Fab")
		)
		(pad "1" smd rect
			(at 0.7366 0 180)
			(size 0.7112 0.8128)
			(layers "B.Cu" "B.Mask" "B.Paste")
			(net "P3V3_AUX")
		)
		(pad "2" smd rect
			(at -0.7366 0 180)
			(size 0.7112 0.8128)
			(layers "B.Cu" "B.Mask" "B.Paste")
			(net "GND")
		)
	)
	(footprint ""
		(layer "B.Cu")
		(at 198.7042 -192.66027)
		(property "Reference" "C546"
			(at 0 0 0)
			(layer "B.SilkS")
			(hide yes)
			(effects
				(font
					(size 1.27 1.27)
				)
				(justify mirror)
			)
		)
		(property "Value" ""
			(at 0 0 0)
			(layer "B.Fab")
			(effects
				(font
					(size 1.27 1.27)
				)
				(justify mirror)
			)
		)
		(duplicate_pad_numbers_are_jumpers no)
		(fp_line
			(start -1.524 -0.762)
			(end -1.524 0.762)
			(stroke
				(width 0.1524)
				(type default)
			)
			(layer "B.SilkS")
		)
		(fp_line
			(start -1.524 0.762)
			(end 1.524 0.762)
			(stroke
				(width 0.1524)
				(type default)
			)
			(layer "B.SilkS")
		)
		(fp_line
			(start 1.524 -0.762)
			(end -1.524 -0.762)
			(stroke
				(width 0.1524)
				(type default)
			)
			(layer "B.SilkS")
		)
		(fp_line
			(start 1.524 0.762)
			(end 1.524 -0.762)
			(stroke
				(width 0.1524)
				(type default)
			)
			(layer "B.SilkS")
		)
		(fp_line
			(start -1.1049 -0.724916)
			(end 1.1049 -0.724916)
			(stroke
				(width 0.1)
				(type default)
			)
			(layer "B.Fab")
		)
		(fp_line
			(start -1.1049 0.724916)
			(end -1.1049 -0.724916)
			(stroke
				(width 0.1)
				(type default)
			)
			(layer "B.Fab")
		)
		(fp_line
			(start 1.1049 -0.724916)
			(end 1.1049 0.724916)
			(stroke
				(width 0.1)
				(type default)
			)
			(layer "B.Fab")
		)
		(fp_line
			(start 1.1049 0.724916)
			(end -1.1049 0.724916)
			(stroke
				(width 0.1)
				(type default)
			)
			(layer "B.Fab")
		)
		(pad "1" smd rect
			(at 0.889 0)
			(size 1.016 1.27)
			(layers "B.Cu" "B.Mask" "B.Paste")
			(net "P12V_MEM_CPU1")
		)
		(pad "2" smd rect
			(at -0.889 0)
			(size 1.016 1.27)
			(layers "B.Cu" "B.Mask" "B.Paste")
			(net "GND")
		)
	)
	(footprint ""
		(layer "B.Cu")
		(at 13.649452 -101.21138 90)
		(property "Reference" "C2031"
			(at 0 0 90)
			(layer "B.SilkS")
			(hide yes)
			(effects
				(font
					(size 1.27 1.27)
				)
				(justify mirror)
			)
		)
		(property "Value" ""
			(at 0 0 90)
			(layer "B.Fab")
			(effects
				(font
					(size 1.27 1.27)
				)
				(justify mirror)
			)
		)
		(duplicate_pad_numbers_are_jumpers no)
		(fp_line
			(start 0.7874 -0.4064)
			(end -0.7874 -0.4064)
			(stroke
				(width 0.1524)
				(type default)
			)
			(layer "B.SilkS")
		)
		(fp_line
			(start -0.7874 -0.4064)
			(end -0.7874 0.4064)
			(stroke
				(width 0.1524)
				(type default)
			)
			(layer "B.SilkS")
		)
		(fp_line
			(start 0.7874 0.4064)
			(end 0.7874 -0.4064)
			(stroke
				(width 0.1524)
				(type default)
			)
			(layer "B.SilkS")
		)
		(fp_line
			(start -0.7874 0.4064)
			(end 0.7874 0.4064)
			(stroke
				(width 0.1524)
				(type default)
			)
			(layer "B.SilkS")
		)
		(fp_line
			(start 0.67945 -0.305054)
			(end 0.12065 -0.305054)
			(stroke
				(width 0.1)
				(type default)
			)
			(layer "B.Fab")
		)
		(fp_line
			(start 0.12065 -0.305054)
			(end 0.12065 -0.2794)
			(stroke
				(width 0.1)
				(type default)
			)
			(layer "B.Fab")
		)
		(fp_line
			(start -0.12065 -0.3048)
			(end -0.67945 -0.3048)
			(stroke
				(width 0.1)
				(type default)
			)
			(layer "B.Fab")
		)
		(fp_line
			(start -0.67945 -0.3048)
			(end -0.67945 0.3048)
			(stroke
				(width 0.1)
				(type default)
			)
			(layer "B.Fab")
		)
		(fp_line
			(start 0.12065 -0.2794)
			(end -0.12065 -0.2794)
			(stroke
				(width 0.1)
				(type default)
			)
			(layer "B.Fab")
		)
		(fp_line
			(start -0.12065 -0.2794)
			(end -0.12065 -0.3048)
			(stroke
				(width 0.1)
				(type default)
			)
			(layer "B.Fab")
		)
		(fp_line
			(start 0.12065 0.2794)
			(end 0.12065 0.3048)
			(stroke
				(width 0.1)
				(type default)
			)
			(layer "B.Fab")
		)
		(fp_line
			(start -0.120396 0.2794)
			(end 0.12065 0.2794)
			(stroke
				(width 0.1)
				(type default)
			)
			(layer "B.Fab")
		)
		(fp_line
			(start 0.67945 0.3048)
			(end 0.67945 -0.305054)
			(stroke
				(width 0.1)
				(type default)
			)
			(layer "B.Fab")
		)
		(fp_line
			(start 0.12065 0.3048)
			(end 0.67945 0.3048)
			(stroke
				(width 0.1)
				(type default)
			)
			(layer "B.Fab")
		)
		(fp_line
			(start -0.120396 0.3048)
			(end -0.120396 0.2794)
			(stroke
				(width 0.1)
				(type default)
			)
			(layer "B.Fab")
		)
		(fp_line
			(start -0.67945 0.3048)
			(end -0.120396 0.3048)
			(stroke
				(width 0.1)
				(type default)
			)
			(layer "B.Fab")
		)
		(pad "1" smd circle
			(at 0.40005 0 270)
			(size 0 0)
			(layers "B.Cu" "B.Mask" "B.Paste")
			(net "P3V3_AUX_USB_HUB")
		)
		(pad "2" smd circle
			(at -0.40005 0 270)
			(size 0 0)
			(layers "B.Cu" "B.Mask" "B.Paste")
			(net "GND")
		)
	)
)
